(kicad_pcb
	(version 20260206)
	(generator "pcbnew")
	(generator_version "10.0")
	(general
		(thickness 1.6)
		(legacy_teardrops no)
	)
	(paper "A4")
	(title_block
		(title "01162023_DA0F0TEBIF0_F0T_Expander_BD_F_brd_V02_OCP.brd")
		(comment 1 "Grand Teton / footprints 9137-9144 of 9728")
	)
	(layers
		(0 "F.Cu" signal "TOP")
		(4 "In1.Cu" signal "GND")
		(6 "In2.Cu" signal "VCC")
		(8 "In3.Cu" signal "VCC1")
		(10 "In4.Cu" signal "GND1")
		(12 "In5.Cu" signal "IN1")
		(14 "In6.Cu" signal "GND2")
		(16 "In7.Cu" signal "IN2")
		(18 "In8.Cu" signal "GND3")
		(20 "In9.Cu" signal "IN3")
		(22 "In10.Cu" signal "GND4")
		(24 "In11.Cu" signal "IN4")
		(26 "In12.Cu" signal "GND5")
		(28 "In13.Cu" signal "IN5")
		(30 "In14.Cu" signal "GND6")
		(32 "In15.Cu" signal "IN6")
		(34 "In16.Cu" signal "GND7")
		(2 "B.Cu" signal "BOTTOM")
		(9 "F.Adhes" user "F.Adhesive")
		(11 "B.Adhes" user "B.Adhesive")
		(13 "F.Paste" user "Package Geometry/Pastemask Top")
		(15 "B.Paste" user "Package Geometry/Pastemask Bottom")
		(5 "F.SilkS" user "Ref Des/Silkscreen Top")
		(7 "B.SilkS" user "Ref Des/Silkscreen Bottom")
		(1 "F.Mask" user "Board Geometry/Soldermask Top")
		(3 "B.Mask" user "Board Geometry/Soldermask Bottom")
		(17 "Dwgs.User" user "User.Drawings")
		(19 "Cmts.User" user "User.Comments")
		(21 "Eco1.User" user "User.Eco1")
		(23 "Eco2.User" user "User.Eco2")
		(25 "Edge.Cuts" user "Board Geometry/Outline")
		(27 "Margin" user)
		(31 "F.CrtYd" user "Package Geometry/Place Bound Top")
		(29 "B.CrtYd" user "Package Geometry/Place Bound Bottom")
		(35 "F.Fab" user "Ref Des/Assembly Top")
		(33 "B.Fab" user "Ref Des/Assembly Bottom")
	)
	(footprint ""
		(layer "B.Cu")
		(at 204.430376 -364.80496 180)
		(property "Reference" "PR2"
			(at 0 0 0)
			(layer "B.SilkS")
			(hide yes)
			(effects
				(font
					(size 1.27 1.27)
				)
				(justify mirror)
			)
		)
		(property "Value" ""
			(at 0 0 0)
			(layer "B.Fab")
			(effects
				(font
					(size 1.27 1.27)
				)
				(justify mirror)
			)
		)
		(duplicate_pad_numbers_are_jumpers no)
		(fp_line
			(start 0.7874 0.4064)
			(end 0.7874 -0.4064)
			(stroke
				(width 0.1524)
				(type default)
			)
			(layer "B.SilkS")
		)
		(fp_line
			(start 0.7874 -0.4064)
			(end -0.7874 -0.4064)
			(stroke
				(width 0.1524)
				(type default)
			)
			(layer "B.SilkS")
		)
		(fp_line
			(start -0.7874 0.4064)
			(end 0.7874 0.4064)
			(stroke
				(width 0.1524)
				(type default)
			)
			(layer "B.SilkS")
		)
		(fp_line
			(start -0.7874 -0.4064)
			(end -0.7874 0.4064)
			(stroke
				(width 0.1524)
				(type default)
			)
			(layer "B.SilkS")
		)
		(fp_line
			(start 0.67945 0.3048)
			(end 0.67945 -0.305054)
			(stroke
				(width 0.1)
				(type default)
			)
			(layer "B.Fab")
		)
		(fp_line
			(start 0.67945 -0.305054)
			(end 0.12065 -0.305054)
			(stroke
				(width 0.1)
				(type default)
			)
			(layer "B.Fab")
		)
		(fp_line
			(start 0.12065 0.3048)
			(end 0.67945 0.3048)
			(stroke
				(width 0.1)
				(type default)
			)
			(layer "B.Fab")
		)
		(fp_line
			(start 0.12065 0.2794)
			(end 0.12065 0.3048)
			(stroke
				(width 0.1)
				(type default)
			)
			(layer "B.Fab")
		)
		(fp_line
			(start 0.12065 -0.2794)
			(end -0.12065 -0.2794)
			(stroke
				(width 0.1)
				(type default)
			)
			(layer "B.Fab")
		)
		(fp_line
			(start 0.12065 -0.305054)
			(end 0.12065 -0.2794)
			(stroke
				(width 0.1)
				(type default)
			)
			(layer "B.Fab")
		)
		(fp_line
			(start -0.120396 0.3048)
			(end -0.120396 0.2794)
			(stroke
				(width 0.1)
				(type default)
			)
			(layer "B.Fab")
		)
		(fp_line
			(start -0.120396 0.2794)
			(end 0.12065 0.2794)
			(stroke
				(width 0.1)
				(type default)
			)
			(layer "B.Fab")
		)
		(fp_line
			(start -0.12065 -0.2794)
			(end -0.12065 -0.3048)
			(stroke
				(width 0.1)
				(type default)
			)
			(layer "B.Fab")
		)
		(fp_line
			(start -0.12065 -0.3048)
			(end -0.67945 -0.3048)
			(stroke
				(width 0.1)
				(type default)
			)
			(layer "B.Fab")
		)
		(fp_line
			(start -0.67945 0.3048)
			(end -0.120396 0.3048)
			(stroke
				(width 0.1)
				(type default)
			)
			(layer "B.Fab")
		)
		(fp_line
			(start -0.67945 -0.3048)
			(end -0.67945 0.3048)
			(stroke
				(width 0.1)
				(type default)
			)
			(layer "B.Fab")
		)
		(pad "1" smd circle
			(at 0.40005 0)
			(size 0 0)
			(layers "B.Cu" "B.Mask" "B.Paste")
			(net "HSC_VOSEN")
		)
		(pad "2" smd circle
			(at -0.40005 0)
			(size 0 0)
			(layers "B.Cu" "B.Mask" "B.Paste")
			(net "P12V_AUX")
		)
	)
	(footprint ""
		(layer "B.Cu")
		(at 415.549842 -290.199826 90)
		(property "Reference" "C1959"
			(at 0 0 90)
			(layer "B.SilkS")
			(hide yes)
			(effects
				(font
					(size 1.27 1.27)
				)
				(justify mirror)
			)
		)
		(property "Value" ""
			(at 0 0 90)
			(layer "B.Fab")
			(effects
				(font
					(size 1.27 1.27)
				)
				(justify mirror)
			)
		)
		(duplicate_pad_numbers_are_jumpers no)
		(fp_line
			(start 0.299974 -0.150114)
			(end -0.299974 -0.150114)
			(stroke
				(width 0.1)
				(type default)
			)
			(layer "B.Fab")
		)
		(fp_line
			(start -0.299974 -0.150114)
			(end -0.299974 0.150114)
			(stroke
				(width 0.1)
				(type default)
			)
			(layer "B.Fab")
		)
		(fp_line
			(start 0.299974 0.150114)
			(end 0.299974 -0.150114)
			(stroke
				(width 0.1)
				(type default)
			)
			(layer "B.Fab")
		)
		(fp_line
			(start -0.299974 0.150114)
			(end 0.299974 0.150114)
			(stroke
				(width 0.1)
				(type default)
			)
			(layer "B.Fab")
		)
		(pad "1" smd rect
			(at 0.2667 0 270)
			(size 0.3048 0.381)
			(layers "B.Cu" "B.Mask" "B.Paste")
			(net "P0V8_SERDES_VDDA_PEX3")
		)
		(pad "2" smd rect
			(at -0.2667 0 270)
			(size 0.3048 0.381)
			(layers "B.Cu" "B.Mask" "B.Paste")
			(net "GND")
		)
	)
	(footprint ""
		(layer "B.Cu")
		(at 350.65716 -318.542416)
		(property "Reference" "C4364"
			(at 0 0 0)
			(layer "B.SilkS")
			(hide yes)
			(effects
				(font
					(size 1.27 1.27)
				)
				(justify mirror)
			)
		)
		(property "Value" ""
			(at 0 0 0)
			(layer "B.Fab")
			(effects
				(font
					(size 1.27 1.27)
				)
				(justify mirror)
			)
		)
		(duplicate_pad_numbers_are_jumpers no)
		(fp_line
			(start -0.299974 -0.150114)
			(end -0.299974 0.150114)
			(stroke
				(width 0.1)
				(type default)
			)
			(layer "B.Fab")
		)
		(fp_line
			(start -0.299974 0.150114)
			(end 0.299974 0.150114)
			(stroke
				(width 0.1)
				(type default)
			)
			(layer "B.Fab")
		)
		(fp_line
			(start 0.299974 -0.150114)
			(end -0.299974 -0.150114)
			(stroke
				(width 0.1)
				(type default)
			)
			(layer "B.Fab")
		)
		(fp_line
			(start 0.299974 0.150114)
			(end 0.299974 -0.150114)
			(stroke
				(width 0.1)
				(type default)
			)
			(layer "B.Fab")
		)
		(pad "1" smd rect
			(at 0.2667 0 180)
			(size 0.3048 0.381)
			(layers "B.Cu" "B.Mask" "B.Paste")
			(net "P0V8_SERDES_VDDA_PEX3")
		)
		(pad "2" smd rect
			(at -0.2667 0 180)
			(size 0.3048 0.381)
			(layers "B.Cu" "B.Mask" "B.Paste")
			(net "GND")
		)
	)
	(footprint ""
		(layer "B.Cu")
		(at 231.131364 -211.54517 180)
		(property "Reference" "R457"
			(at 0 0 0)
			(layer "B.SilkS")
			(hide yes)
			(effects
				(font
					(size 1.27 1.27)
				)
				(justify mirror)
			)
		)
		(property "Value" ""
			(at 0 0 0)
			(layer "B.Fab")
			(effects
				(font
					(size 1.27 1.27)
				)
				(justify mirror)
			)
		)
		(duplicate_pad_numbers_are_jumpers no)
		(fp_line
			(start 1.2954 0.5842)
			(end 1.2954 -0.5842)
			(stroke
				(width 0.1524)
				(type default)
			)
			(layer "B.SilkS")
		)
		(fp_line
			(start 1.2954 -0.5842)
			(end -1.2954 -0.5842)
			(stroke
				(width 0.1524)
				(type default)
			)
			(layer "B.SilkS")
		)
		(fp_line
			(start -1.2954 0.5842)
			(end 1.2954 0.5842)
			(stroke
				(width 0.1524)
				(type default)
			)
			(layer "B.SilkS")
		)
		(fp_line
			(start -1.2954 -0.5842)
			(end -1.2954 0.5842)
			(stroke
				(width 0.1524)
				(type default)
			)
			(layer "B.SilkS")
		)
		(fp_line
			(start 1.1938 0.4064)
			(end 1.1938 -0.406654)
			(stroke
				(width 0.1)
				(type default)
			)
			(layer "B.Fab")
		)
		(fp_line
			(start 1.1938 -0.406654)
			(end 0.8636 -0.406654)
			(stroke
				(width 0.1)
				(type default)
			)
			(layer "B.Fab")
		)
		(fp_line
			(start 0.8636 0.4572)
			(end 0.8636 0.4318)
			(stroke
				(width 0.1)
				(type default)
			)
			(layer "B.Fab")
		)
		(fp_line
			(start 0.8636 0.4318)
			(end 0.8636 0.4064)
			(stroke
				(width 0.1)
				(type default)
			)
			(layer "B.Fab")
		)
		(fp_line
			(start 0.8636 0.4064)
			(end 1.1938 0.4064)
			(stroke
				(width 0.1)
				(type default)
			)
			(layer "B.Fab")
		)
		(fp_line
			(start 0.8636 -0.406654)
			(end 0.8636 -0.4572)
			(stroke
				(width 0.1)
				(type default)
			)
			(layer "B.Fab")
		)
		(fp_line
			(start 0.8636 -0.4572)
			(end -0.8636 -0.4572)
			(stroke
				(width 0.1)
				(type default)
			)
			(layer "B.Fab")
		)
		(fp_line
			(start -0.8636 0.4572)
			(end 0.8636 0.4572)
			(stroke
				(width 0.1)
				(type default)
			)
			(layer "B.Fab")
		)
		(fp_line
			(start -0.8636 0.4064)
			(end -0.8636 0.4572)
			(stroke
				(width 0.1)
				(type default)
			)
			(layer "B.Fab")
		)
		(fp_line
			(start -0.8636 -0.406654)
			(end -1.1938 -0.406654)
			(stroke
				(width 0.1)
				(type default)
			)
			(layer "B.Fab")
		)
		(fp_line
			(start -0.8636 -0.4572)
			(end -0.8636 -0.406654)
			(stroke
				(width 0.1)
				(type default)
			)
			(layer "B.Fab")
		)
		(fp_line
			(start -1.1938 0.4064)
			(end -0.8636 0.4064)
			(stroke
				(width 0.1)
				(type default)
			)
			(layer "B.Fab")
		)
		(fp_line
			(start -1.1938 -0.406654)
			(end -1.1938 0.4064)
			(stroke
				(width 0.1)
				(type default)
			)
			(layer "B.Fab")
		)
		(pad "1" smd rect
			(at 0.7366 0 90)
			(size 0.7112 0.8128)
			(layers "B.Cu" "B.Mask" "B.Paste")
			(net "P3V3_BIC_SPI")
		)
		(pad "2" smd rect
			(at -0.7366 0 90)
			(size 0.7112 0.8128)
			(layers "B.Cu" "B.Mask" "B.Paste")
			(net "P3V3_AUX")
		)
	)
	(footprint ""
		(layer "B.Cu")
		(at 349.780098 -282.040584 90)
		(property "Reference" "PR154"
			(at 0 0 90)
			(layer "B.SilkS")
			(hide yes)
			(effects
				(font
					(size 1.27 1.27)
				)
				(justify mirror)
			)
		)
		(property "Value" ""
			(at 0 0 90)
			(layer "B.Fab")
			(effects
				(font
					(size 1.27 1.27)
				)
				(justify mirror)
			)
		)
		(duplicate_pad_numbers_are_jumpers no)
		(fp_line
			(start 0.7874 -0.4064)
			(end -0.7874 -0.4064)
			(stroke
				(width 0.1524)
				(type default)
			)
			(layer "B.SilkS")
		)
		(fp_line
			(start -0.7874 -0.4064)
			(end -0.7874 0.4064)
			(stroke
				(width 0.1524)
				(type default)
			)
			(layer "B.SilkS")
		)
		(fp_line
			(start 0.7874 0.4064)
			(end 0.7874 -0.4064)
			(stroke
				(width 0.1524)
				(type default)
			)
			(layer "B.SilkS")
		)
		(fp_line
			(start -0.7874 0.4064)
			(end 0.7874 0.4064)
			(stroke
				(width 0.1524)
				(type default)
			)
			(layer "B.SilkS")
		)
		(fp_line
			(start 0.67945 -0.305054)
			(end 0.12065 -0.305054)
			(stroke
				(width 0.1)
				(type default)
			)
			(layer "B.Fab")
		)
		(fp_line
			(start 0.12065 -0.305054)
			(end 0.12065 -0.2794)
			(stroke
				(width 0.1)
				(type default)
			)
			(layer "B.Fab")
		)
		(fp_line
			(start -0.12065 -0.3048)
			(end -0.67945 -0.3048)
			(stroke
				(width 0.1)
				(type default)
			)
			(layer "B.Fab")
		)
		(fp_line
			(start -0.67945 -0.3048)
			(end -0.67945 0.3048)
			(stroke
				(width 0.1)
				(type default)
			)
			(layer "B.Fab")
		)
		(fp_line
			(start 0.12065 -0.2794)
			(end -0.12065 -0.2794)
			(stroke
				(width 0.1)
				(type default)
			)
			(layer "B.Fab")
		)
		(fp_line
			(start -0.12065 -0.2794)
			(end -0.12065 -0.3048)
			(stroke
				(width 0.1)
				(type default)
			)
			(layer "B.Fab")
		)
		(fp_line
			(start 0.12065 0.2794)
			(end 0.12065 0.3048)
			(stroke
				(width 0.1)
				(type default)
			)
			(layer "B.Fab")
		)
		(fp_line
			(start -0.120396 0.2794)
			(end 0.12065 0.2794)
			(stroke
				(width 0.1)
				(type default)
			)
			(layer "B.Fab")
		)
		(fp_line
			(start 0.67945 0.3048)
			(end 0.67945 -0.305054)
			(stroke
				(width 0.1)
				(type default)
			)
			(layer "B.Fab")
		)
		(fp_line
			(start 0.12065 0.3048)
			(end 0.67945 0.3048)
			(stroke
				(width 0.1)
				(type default)
			)
			(layer "B.Fab")
		)
		(fp_line
			(start -0.120396 0.3048)
			(end -0.120396 0.2794)
			(stroke
				(width 0.1)
				(type default)
			)
			(layer "B.Fab")
		)
		(fp_line
			(start -0.67945 0.3048)
			(end -0.120396 0.3048)
			(stroke
				(width 0.1)
				(type default)
			)
			(layer "B.Fab")
		)
		(pad "1" smd circle
			(at 0.40005 0 270)
			(size 0 0)
			(layers "B.Cu" "B.Mask" "B.Paste")
			(net "SW_P0V8_PEX2_VOS2")
		)
		(pad "2" smd circle
			(at -0.40005 0 270)
			(size 0 0)
			(layers "B.Cu" "B.Mask" "B.Paste")
			(net "P0V8_PEX2")
		)
	)
	(footprint ""
		(layer "B.Cu")
		(at 283.299916 -288.299906 90)
		(property "Reference" "C3271"
			(at 0 0 90)
			(layer "B.SilkS")
			(hide yes)
			(effects
				(font
					(size 1.27 1.27)
				)
				(justify mirror)
			)
		)
		(property "Value" ""
			(at 0 0 90)
			(layer "B.Fab")
			(effects
				(font
					(size 1.27 1.27)
				)
				(justify mirror)
			)
		)
		(duplicate_pad_numbers_are_jumpers no)
		(fp_line
			(start 0.299974 -0.150114)
			(end -0.299974 -0.150114)
			(stroke
				(width 0.1)
				(type default)
			)
			(layer "B.Fab")
		)
		(fp_line
			(start -0.299974 -0.150114)
			(end -0.299974 0.150114)
			(stroke
				(width 0.1)
				(type default)
			)
			(layer "B.Fab")
		)
		(fp_line
			(start 0.299974 0.150114)
			(end 0.299974 -0.150114)
			(stroke
				(width 0.1)
				(type default)
			)
			(layer "B.Fab")
		)
		(fp_line
			(start -0.299974 0.150114)
			(end 0.299974 0.150114)
			(stroke
				(width 0.1)
				(type default)
			)
			(layer "B.Fab")
		)
		(pad "1" smd rect
			(at 0.2667 0 270)
			(size 0.3048 0.381)
			(layers "B.Cu" "B.Mask" "B.Paste")
			(net "P1V25_PEX2")
		)
		(pad "2" smd rect
			(at -0.2667 0 270)
			(size 0.3048 0.381)
			(layers "B.Cu" "B.Mask" "B.Paste")
			(net "GND")
		)
	)
	(footprint ""
		(layer "B.Cu")
		(at 217.235786 -218.302586)
		(property "Reference" "R1504"
			(at 0 0 0)
			(layer "B.SilkS")
			(hide yes)
			(effects
				(font
					(size 1.27 1.27)
				)
				(justify mirror)
			)
		)
		(property "Value" ""
			(at 0 0 0)
			(layer "B.Fab")
			(effects
				(font
					(size 1.27 1.27)
				)
				(justify mirror)
			)
		)
		(duplicate_pad_numbers_are_jumpers no)
		(fp_line
			(start -0.7874 -0.4064)
			(end -0.7874 0.4064)
			(stroke
				(width 0.1524)
				(type default)
			)
			(layer "B.SilkS")
		)
		(fp_line
			(start -0.7874 0.4064)
			(end 0.7874 0.4064)
			(stroke
				(width 0.1524)
				(type default)
			)
			(layer "B.SilkS")
		)
		(fp_line
			(start 0.7874 -0.4064)
			(end -0.7874 -0.4064)
			(stroke
				(width 0.1524)
				(type default)
			)
			(layer "B.SilkS")
		)
		(fp_line
			(start 0.7874 0.4064)
			(end 0.7874 -0.4064)
			(stroke
				(width 0.1524)
				(type default)
			)
			(layer "B.SilkS")
		)
		(fp_line
			(start -0.67945 -0.3048)
			(end -0.67945 0.3048)
			(stroke
				(width 0.1)
				(type default)
			)
			(layer "B.Fab")
		)
		(fp_line
			(start -0.67945 0.3048)
			(end -0.120396 0.3048)
			(stroke
				(width 0.1)
				(type default)
			)
			(layer "B.Fab")
		)
		(fp_line
			(start -0.12065 -0.3048)
			(end -0.67945 -0.3048)
			(stroke
				(width 0.1)
				(type default)
			)
			(layer "B.Fab")
		)
		(fp_line
			(start -0.12065 -0.2794)
			(end -0.12065 -0.3048)
			(stroke
				(width 0.1)
				(type default)
			)
			(layer "B.Fab")
		)
		(fp_line
			(start -0.120396 0.2794)
			(end 0.12065 0.2794)
			(stroke
				(width 0.1)
				(type default)
			)
			(layer "B.Fab")
		)
		(fp_line
			(start -0.120396 0.3048)
			(end -0.120396 0.2794)
			(stroke
				(width 0.1)
				(type default)
			)
			(layer "B.Fab")
		)
		(fp_line
			(start 0.12065 -0.305054)
			(end 0.12065 -0.2794)
			(stroke
				(width 0.1)
				(type default)
			)
			(layer "B.Fab")
		)
		(fp_line
			(start 0.12065 -0.2794)
			(end -0.12065 -0.2794)
			(stroke
				(width 0.1)
				(type default)
			)
			(layer "B.Fab")
		)
		(fp_line
			(start 0.12065 0.2794)
			(end 0.12065 0.3048)
			(stroke
				(width 0.1)
				(type default)
			)
			(layer "B.Fab")
		)
		(fp_line
			(start 0.12065 0.3048)
			(end 0.67945 0.3048)
			(stroke
				(width 0.1)
				(type default)
			)
			(layer "B.Fab")
		)
		(fp_line
			(start 0.67945 -0.305054)
			(end 0.12065 -0.305054)
			(stroke
				(width 0.1)
				(type default)
			)
			(layer "B.Fab")
		)
		(fp_line
			(start 0.67945 0.3048)
			(end 0.67945 -0.305054)
			(stroke
				(width 0.1)
				(type default)
			)
			(layer "B.Fab")
		)
		(pad "1" smd circle
			(at 0.40005 0 180)
			(size 0 0)
			(layers "B.Cu" "B.Mask" "B.Paste")
			(net "SMB_NIC7_SCL")
		)
		(pad "2" smd circle
			(at -0.40005 0 180)
			(size 0 0)
			(layers "B.Cu" "B.Mask" "B.Paste")
			(net "SMB_NIC7_R_SCL")
		)
	)
	(footprint ""
		(layer "B.Cu")
		(at 301.349918 -294.4749 180)
		(property "Reference" "C1672"
			(at 0 0 0)
			(layer "B.SilkS")
			(hide yes)
			(effects
				(font
					(size 1.27 1.27)
				)
				(justify mirror)
			)
		)
		(property "Value" ""
			(at 0 0 0)
			(layer "B.Fab")
			(effects
				(font
					(size 1.27 1.27)
				)
				(justify mirror)
			)
		)
		(duplicate_pad_numbers_are_jumpers no)
		(fp_line
			(start 0.299974 0.150114)
			(end 0.299974 -0.150114)
			(stroke
				(width 0.1)
				(type default)
			)
			(layer "B.Fab")
		)
		(fp_line
			(start 0.299974 -0.150114)
			(end -0.299974 -0.150114)
			(stroke
				(width 0.1)
				(type default)
			)
			(layer "B.Fab")
		)
		(fp_line
			(start -0.299974 0.150114)
			(end 0.299974 0.150114)
			(stroke
				(width 0.1)
				(type default)
			)
			(layer "B.Fab")
		)
		(fp_line
			(start -0.299974 -0.150114)
			(end -0.299974 0.150114)
			(stroke
				(width 0.1)
				(type default)
			)
			(layer "B.Fab")
		)
		(pad "1" smd rect
			(at 0.2667 0)
			(size 0.3048 0.381)
			(layers "B.Cu" "B.Mask" "B.Paste")
			(net "P0V8_SERDES_VDDA_PEX2")
		)
		(pad "2" smd rect
			(at -0.2667 0)
			(size 0.3048 0.381)
			(layers "B.Cu" "B.Mask" "B.Paste")
			(net "GND")
		)
	)
)
